(kicad_pcb
	(version 20241229)
	(generator "pcbnew")
	(generator_version "9.0")
	(general
		(thickness 1.62)
		(legacy_teardrops no)
	)
	(paper "A4")
	(title_block
		(title "OCuLink to 10GbE adapter")
		(date "2026-02-23")
		(rev "1.1.0")
		(company "Antmicro Ltd")
		(comment 1 "www.antmicro.com")
		(comment 9 "footprints 270-275 of 510")
	)
	(layers
		(0 "F.Cu" signal)
		(4 "In1.Cu" signal)
		(6 "In2.Cu" signal)
		(8 "In3.Cu" signal)
		(10 "In4.Cu" signal)
		(12 "In5.Cu" signal)
		(14 "In6.Cu" signal)
		(2 "B.Cu" signal)
		(9 "F.Adhes" user "F.Adhesive")
		(11 "B.Adhes" user "B.Adhesive")
		(13 "F.Paste" user)
		(15 "B.Paste" user)
		(5 "F.SilkS" user "F.Silkscreen")
		(7 "B.SilkS" user "B.Silkscreen")
		(1 "F.Mask" user)
		(3 "B.Mask" user)
		(17 "Dwgs.User" user "User.Drawings")
		(19 "Cmts.User" user "User.Comments")
		(21 "Eco1.User" user "User.Eco1")
		(23 "Eco2.User" user "User.Eco2")
		(25 "Edge.Cuts" user)
		(27 "Margin" user)
		(31 "F.CrtYd" user "F.Courtyard")
		(29 "B.CrtYd" user "B.Courtyard")
		(35 "F.Fab" user)
		(33 "B.Fab" user)
	)
	(footprint "antmicro-footprints:C_0603_1608Metric"
		(layer "F.Cu")
		(at 72.45 100.95 -90)
		(descr "Capacitor SMD 0603")
		(tags "capacitor 0603")
		(property "Reference" "C180"
			(at -1.39 -0.74 90)
			(layer "F.SilkS")
			(effects
				(font
					(size 0.7 0.7)
					(thickness 0.15)
				)
				(justify right top)
			)
		)
		(property "Value" "C_47u_0603"
			(at -1.42757 1.770288 90)
			(layer "F.Fab")
			(hide yes)
			(effects
				(font
					(size 0.7 0.7)
					(thickness 0.15)
				)
				(justify right top)
			)
		)
		(property "Datasheet" "https://www.murata.com/products/productdetail?partno=GRM188R60J476ME15%23"
			(at 0 0 90)
			(layer "F.Fab")
			(hide yes)
			(effects
				(font
					(size 1.27 1.27)
					(thickness 0.15)
				)
			)
		)
		(property "Description" "SMD Multilayer Ceramic Capacitor, 47 µF, 6.3 V, 0603 [1608 Metric], ± 20%, X5R, GRM Series"
			(at 0 0 90)
			(layer "F.Fab")
			(hide yes)
			(effects
				(font
					(size 1.27 1.27)
					(thickness 0.15)
				)
			)
		)
		(property "MPN" "GRM188R60J476ME15D"
			(at 0 0 270)
			(unlocked yes)
			(layer "F.Fab")
			(hide yes)
			(effects
				(font
					(size 1 1)
					(thickness 0.15)
				)
			)
		)
		(property "Manufacturer" "Murata"
			(at 0 0 270)
			(unlocked yes)
			(layer "F.Fab")
			(hide yes)
			(effects
				(font
					(size 1 1)
					(thickness 0.15)
				)
			)
		)
		(property "License" "Apache-2.0"
			(at 0 0 270)
			(unlocked yes)
			(layer "F.Fab")
			(hide yes)
			(effects
				(font
					(size 1 1)
					(thickness 0.15)
				)
			)
		)
		(property "Author" "Antmicro"
			(at 0 0 270)
			(unlocked yes)
			(layer "F.Fab")
			(hide yes)
			(effects
				(font
					(size 1 1)
					(thickness 0.15)
				)
			)
		)
		(property "Val" "47u"
			(at 0 0 270)
			(unlocked yes)
			(layer "F.Fab")
			(hide yes)
			(effects
				(font
					(size 1 1)
					(thickness 0.15)
				)
			)
		)
		(property "Voltage" ""
			(at 0 0 270)
			(unlocked yes)
			(layer "F.Fab")
			(hide yes)
			(effects
				(font
					(size 1 1)
					(thickness 0.15)
				)
			)
		)
		(property "Dielectric" ""
			(at 0 0 270)
			(unlocked yes)
			(layer "F.Fab")
			(hide yes)
			(effects
				(font
					(size 1 1)
					(thickness 0.15)
				)
			)
		)
		(sheetname "/X710-AT2 power/")
		(sheetfile "x710-at2-power.kicad_sch")
		(attr smd)
		(fp_line
			(start -0.15 0.4)
			(end 0.15 0.4)
			(stroke
				(width 0.15)
				(type solid)
			)
			(layer "F.SilkS")
		)
		(fp_line
			(start -0.15 -0.4)
			(end 0.15 -0.4)
			(stroke
				(width 0.15)
				(type solid)
			)
			(layer "F.SilkS")
		)
		(fp_rect
			(start -1.25 -0.65)
			(end 1.25 0.65)
			(stroke
				(width 0.05)
				(type solid)
			)
			(fill no)
			(layer "F.CrtYd")
		)
		(fp_rect
			(start -0.8 -0.4)
			(end 0.8 0.4)
			(stroke
				(width 0.15)
				(type solid)
			)
			(fill no)
			(layer "F.Fab")
		)
		(pad "1" smd roundrect
			(at -0.7 0 270)
			(size 0.8 1)
			(layers "F.Cu" "F.Mask" "F.Paste")
			(roundrect_rratio 0.2)
			(net 28 "GND")
			(pintype "passive")
		)
		(pad "2" smd roundrect
			(at 0.7 0 270)
			(size 0.8 1)
			(layers "F.Cu" "F.Mask" "F.Paste")
			(roundrect_rratio 0.2)
			(net 12 "XFI_VDD")
			(pintype "passive")
		)
	)
	(footprint "antmicro-footprints:C_0603_1608Metric"
		(layer "F.Cu")
		(at 72.45 98.3 90)
		(descr "Capacitor SMD 0603")
		(tags "capacitor 0603")
		(property "Reference" "C140"
			(at 1.08 0.32 90)
			(layer "F.SilkS")
			(effects
				(font
					(size 0.7 0.7)
					(thickness 0.15)
				)
				(justify left bottom)
			)
		)
		(property "Value" "C_10u_10V_X7R_0603"
			(at -1.42757 1.770288 90)
			(layer "F.Fab")
			(hide yes)
			(effects
				(font
					(size 0.7 0.7)
					(thickness 0.15)
				)
				(justify left bottom)
			)
		)
		(property "Datasheet" "https://www.murata.com/products/productdetail?partno=GRM188Z71A106KA73%23"
			(at 0 0 90)
			(layer "F.Fab")
			(hide yes)
			(effects
				(font
					(size 1.27 1.27)
					(thickness 0.15)
				)
			)
		)
		(property "Description" "SMD Multilayer Ceramic Capacitor,  10µF, 10V, 0603, ±10%, X7R"
			(at 0 0 90)
			(layer "F.Fab")
			(hide yes)
			(effects
				(font
					(size 1.27 1.27)
					(thickness 0.15)
				)
			)
		)
		(property "MPN" "GRM188Z71A106KA73D"
			(at 0 0 90)
			(unlocked yes)
			(layer "F.Fab")
			(hide yes)
			(effects
				(font
					(size 1 1)
					(thickness 0.15)
				)
			)
		)
		(property "Val" "10u"
			(at 0 0 90)
			(unlocked yes)
			(layer "F.Fab")
			(hide yes)
			(effects
				(font
					(size 1 1)
					(thickness 0.15)
				)
			)
		)
		(property "Voltage" "10V"
			(at 0 0 90)
			(unlocked yes)
			(layer "F.Fab")
			(hide yes)
			(effects
				(font
					(size 1 1)
					(thickness 0.15)
				)
			)
		)
		(property "Dielectric" "X7R"
			(at 0 0 90)
			(unlocked yes)
			(layer "F.Fab")
			(hide yes)
			(effects
				(font
					(size 1 1)
					(thickness 0.15)
				)
			)
		)
		(property "Manufacturer" "Murata"
			(at 0 0 90)
			(unlocked yes)
			(layer "F.Fab")
			(hide yes)
			(effects
				(font
					(size 1 1)
					(thickness 0.15)
				)
			)
		)
		(property "License" "Apache-2.0"
			(at 0 0 90)
			(unlocked yes)
			(layer "F.Fab")
			(hide yes)
			(effects
				(font
					(size 1 1)
					(thickness 0.15)
				)
			)
		)
		(property "Author" "Antmicro"
			(at 0 0 90)
			(unlocked yes)
			(layer "F.Fab")
			(hide yes)
			(effects
				(font
					(size 1 1)
					(thickness 0.15)
				)
			)
		)
		(sheetname "/X710-AT2 power/")
		(sheetfile "x710-at2-power.kicad_sch")
		(attr smd)
		(fp_line
			(start -0.15 -0.4)
			(end 0.15 -0.4)
			(stroke
				(width 0.15)
				(type solid)
			)
			(layer "F.SilkS")
		)
		(fp_line
			(start -0.15 0.4)
			(end 0.15 0.4)
			(stroke
				(width 0.15)
				(type solid)
			)
			(layer "F.SilkS")
		)
		(fp_rect
			(start -1.25 -0.65)
			(end 1.25 0.65)
			(stroke
				(width 0.05)
				(type solid)
			)
			(fill no)
			(layer "F.CrtYd")
		)
		(fp_rect
			(start -0.8 -0.4)
			(end 0.8 0.4)
			(stroke
				(width 0.15)
				(type solid)
			)
			(fill no)
			(layer "F.Fab")
		)
		(pad "1" smd roundrect
			(at -0.7 0 90)
			(size 0.8 1)
			(layers "F.Cu" "F.Mask" "F.Paste")
			(roundrect_rratio 0.2)
			(net 28 "GND")
			(pintype "passive")
		)
		(pad "2" smd roundrect
			(at 0.7 0 90)
			(size 0.8 1)
			(layers "F.Cu" "F.Mask" "F.Paste")
			(roundrect_rratio 0.2)
			(net 10 "AVDDH")
			(pintype "passive")
		)
	)
	(footprint "antmicro-footprints:C_0603_1608Metric_EIA"
		(layer "F.Cu")
		(at 60.649999 84.1)
		(descr "Capacitor SMD 0603, IPC-7351 Density Level A")
		(tags "Capacitor 0603")
		(property "Reference" "C16"
			(at -0.749999 -1.54 0)
			(layer "F.SilkS")
			(effects
				(font
					(size 0.7 0.7)
					(thickness 0.15)
				)
				(justify left bottom)
			)
		)
		(property "Value" "C_22u_16V_0603"
			(at -1.42757 1.770288 0)
			(layer "F.Fab")
			(hide yes)
			(effects
				(font
					(size 0.7 0.7)
					(thickness 0.15)
				)
				(justify left bottom)
			)
		)
		(property "Datasheet" "https://product.samsungsem.com/mlcc/CL10A226MO7JZN.do"
			(at 0 0 0)
			(layer "F.Fab")
			(hide yes)
			(effects
				(font
					(size 1.27 1.27)
					(thickness 0.15)
				)
			)
		)
		(property "Description" "SMD Multilayer Ceramic Capacitor"
			(at 0 0 0)
			(layer "F.Fab")
			(hide yes)
			(effects
				(font
					(size 1.27 1.27)
					(thickness 0.15)
				)
			)
		)
		(property "MPN" "CL10A226MO7JZNC"
			(at 0 0 0)
			(unlocked yes)
			(layer "F.Fab")
			(hide yes)
			(effects
				(font
					(size 1 1)
					(thickness 0.15)
				)
			)
		)
		(property "Manufacturer" "Samsung Electro-Mechanics"
			(at 0 0 0)
			(unlocked yes)
			(layer "F.Fab")
			(hide yes)
			(effects
				(font
					(size 1 1)
					(thickness 0.15)
				)
			)
		)
		(property "License" "Apache-2.0"
			(at 0 0 0)
			(unlocked yes)
			(layer "F.Fab")
			(hide yes)
			(effects
				(font
					(size 1 1)
					(thickness 0.15)
				)
			)
		)
		(property "Author" "Antmicro"
			(at 0 0 0)
			(unlocked yes)
			(layer "F.Fab")
			(hide yes)
			(effects
				(font
					(size 1 1)
					(thickness 0.15)
				)
			)
		)
		(property "Val" "22u"
			(at 0 0 0)
			(unlocked yes)
			(layer "F.Fab")
			(hide yes)
			(effects
				(font
					(size 1 1)
					(thickness 0.15)
				)
			)
		)
		(property "Voltage" "16V"
			(at 0 0 0)
			(unlocked yes)
			(layer "F.Fab")
			(hide yes)
			(effects
				(font
					(size 1 1)
					(thickness 0.15)
				)
			)
		)
		(property "Dielectric" ""
			(at 0 0 0)
			(unlocked yes)
			(layer "F.Fab")
			(hide yes)
			(effects
				(font
					(size 1 1)
					(thickness 0.15)
				)
			)
		)
		(property "Public" "False"
			(at 0 0 0)
			(unlocked yes)
			(layer "F.Fab")
			(hide yes)
			(effects
				(font
					(size 1 1)
					(thickness 0.15)
				)
			)
		)
		(sheetname "/Power/")
		(sheetfile "power.kicad_sch")
		(attr smd)
		(fp_line
			(start -0.15 -0.55)
			(end 0.15 -0.55)
			(stroke
				(width 0.15)
				(type solid)
			)
			(layer "F.SilkS")
		)
		(fp_line
			(start -0.15 0.55)
			(end 0.15 0.55)
			(stroke
				(width 0.15)
				(type solid)
			)
			(layer "F.SilkS")
		)
		(fp_rect
			(start -1.25 -0.65)
			(end 1.25 0.65)
			(stroke
				(width 0.05)
				(type solid)
			)
			(fill no)
			(layer "F.CrtYd")
		)
		(fp_rect
			(start -0.8 -0.45)
			(end 0.8 0.45)
			(stroke
				(width 0.15)
				(type solid)
			)
			(fill no)
			(layer "F.Fab")
		)
		(pad "1" smd roundrect
			(at -0.7 0)
			(size 0.8 1.1)
			(layers "F.Cu" "F.Mask" "F.Paste")
			(roundrect_rratio 0.2)
			(net 28 "GND")
			(pintype "passive")
		)
		(pad "2" smd roundrect
			(at 0.7 0)
			(size 0.8 1.1)
			(layers "F.Cu" "F.Mask" "F.Paste")
			(roundrect_rratio 0.2)
			(net 303 "/Power/+VCCD_OUT")
			(pintype "passive")
		)
	)
	(footprint "antmicro-footprints:R_0402_1005Metric"
		(layer "F.Cu")
		(at 57.15 120.4 180)
		(descr "Resistor SMD 0402")
		(tags "resistor SMD 0402")
		(property "Reference" "R147"
			(at -1.5 -0.772697 0)
			(layer "F.SilkS")
			(effects
				(font
					(size 0.7 0.7)
					(thickness 0.15)
				)
				(justify right top)
			)
		)
		(property "Value" "R_1k_0402"
			(at -1.011843 1.772046 0)
			(layer "F.Fab")
			(hide yes)
			(effects
				(font
					(size 0.7 0.7)
					(thickness 0.15)
				)
				(justify right top)
			)
		)
		(property "Datasheet" "https://www.bourns.com/docs/product-datasheets/cr.pdf"
			(at 0 0 0)
			(layer "F.Fab")
			(hide yes)
			(effects
				(font
					(size 1.27 1.27)
					(thickness 0.15)
				)
			)
		)
		(property "Description" "SMD Chip Resistor, 1 kohm, ± 1%, 63 mW, 0402 [1005 Metric], Thick Film, General Purpose"
			(at 0 0 0)
			(layer "F.Fab")
			(hide yes)
			(effects
				(font
					(size 1.27 1.27)
					(thickness 0.15)
				)
			)
		)
		(property "MPN" "CR0402-FX-1001GLF"
			(at 0 0 180)
			(unlocked yes)
			(layer "F.Fab")
			(hide yes)
			(effects
				(font
					(size 1 1)
					(thickness 0.15)
				)
			)
		)
		(property "Manufacturer" "Bourns"
			(at 0 0 180)
			(unlocked yes)
			(layer "F.Fab")
			(hide yes)
			(effects
				(font
					(size 1 1)
					(thickness 0.15)
				)
			)
		)
		(property "License" "Apache-2.0"
			(at 0 0 180)
			(unlocked yes)
			(layer "F.Fab")
			(hide yes)
			(effects
				(font
					(size 1 1)
					(thickness 0.15)
				)
			)
		)
		(property "Author" "Antmicro"
			(at 0 0 180)
			(unlocked yes)
			(layer "F.Fab")
			(hide yes)
			(effects
				(font
					(size 1 1)
					(thickness 0.15)
				)
			)
		)
		(property "Val" "1k"
			(at 0 0 180)
			(unlocked yes)
			(layer "F.Fab")
			(hide yes)
			(effects
				(font
					(size 1 1)
					(thickness 0.15)
				)
			)
		)
		(property "Tolerance" "1%"
			(at 0 0 180)
			(unlocked yes)
			(layer "F.Fab")
			(hide yes)
			(effects
				(font
					(size 1 1)
					(thickness 0.15)
				)
			)
		)
		(sheetname "/Power/")
		(sheetfile "power.kicad_sch")
		(attr smd)
		(fp_poly
			(pts
				(xy -0.925 -0.47) (xy 0.925 -0.47) (xy 0.925 0.47) (xy -0.925 0.47)
			)
			(stroke
				(width 0.05)
				(type default)
			)
			(fill no)
			(layer "F.CrtYd")
		)
		(fp_poly
			(pts
				(xy -0.5 -0.25) (xy 0.5 -0.25) (xy 0.5 0.25) (xy -0.5 0.25)
			)
			(stroke
				(width 0.15)
				(type solid)
			)
			(fill no)
			(layer "F.Fab")
		)
		(pad "1" smd roundrect
			(at -0.48 0 180)
			(size 0.59 0.64)
			(layers "F.Cu" "F.Mask" "F.Paste")
			(roundrect_rratio 0.25)
			(net 418 "Net-(Q8-C)")
			(pintype "passive")
		)
		(pad "2" smd roundrect
			(at 0.48 0 180)
			(size 0.59 0.64)
			(layers "F.Cu" "F.Mask" "F.Paste")
			(roundrect_rratio 0.25)
			(net 413 "Net-(D19-C)")
			(pintype "passive")
		)
	)
	(footprint "antmicro-footprints:C_0402_1005Metric"
		(layer "F.Cu")
		(at 102 65.285 -90)
		(descr "Capacitor SMD 0402")
		(tags "capacitor SMD 0402")
		(property "Reference" "C193"
			(at 0.792273 -0.399995 270)
			(layer "F.SilkS")
			(effects
				(font
					(size 0.7 0.7)
					(thickness 0.15)
				)
				(justify right bottom)
			)
		)
		(property "Value" "C_220n_16V_0402"
			(at -1.022927 2.155213 270)
			(layer "F.Fab")
			(hide yes)
			(effects
				(font
					(size 0.7 0.7)
					(thickness 0.15)
				)
				(justify left bottom)
			)
		)
		(property "Datasheet" "https://www.murata.com/products/productdetail?partno=GRM155R71C224KA12%23"
			(at 0 0 270)
			(layer "F.Fab")
			(hide yes)
			(effects
				(font
					(size 1.27 1.27)
					(thickness 0.15)
				)
			)
		)
		(property "Description" "SMD Multilayer Ceramic Capacitor, 0.22 µF, 16 V, 0402 [1005 Metric], ± 10%, X7R, GRM Series"
			(at 0 0 270)
			(layer "F.Fab")
			(hide yes)
			(effects
				(font
					(size 1.27 1.27)
					(thickness 0.15)
				)
			)
		)
		(property "MPN" "GRM155R71C224KA12D"
			(at 0 0 270)
			(unlocked yes)
			(layer "F.Fab")
			(hide yes)
			(effects
				(font
					(size 1 1)
					(thickness 0.15)
				)
			)
		)
		(property "Manufacturer" "Murata"
			(at 0 0 270)
			(unlocked yes)
			(layer "F.Fab")
			(hide yes)
			(effects
				(font
					(size 1 1)
					(thickness 0.15)
				)
			)
		)
		(property "License" "Apache-2.0"
			(at 0 0 270)
			(unlocked yes)
			(layer "F.Fab")
			(hide yes)
			(effects
				(font
					(size 1 1)
					(thickness 0.15)
				)
			)
		)
		(property "Author" "Antmicro"
			(at 0 0 270)
			(unlocked yes)
			(layer "F.Fab")
			(hide yes)
			(effects
				(font
					(size 1 1)
					(thickness 0.15)
				)
			)
		)
		(property "Val" "220n"
			(at 0 0 270)
			(unlocked yes)
			(layer "F.Fab")
			(hide yes)
			(effects
				(font
					(size 1 1)
					(thickness 0.15)
				)
			)
		)
		(property "Voltage" "16V"
			(at 0 0 270)
			(unlocked yes)
			(layer "F.Fab")
			(hide yes)
			(effects
				(font
					(size 1 1)
					(thickness 0.15)
				)
			)
		)
		(property "Dielectric" "X7R"
			(at 0 0 270)
			(unlocked yes)
			(layer "F.Fab")
			(hide yes)
			(effects
				(font
					(size 1 1)
					(thickness 0.15)
				)
			)
		)
		(sheetname "/X710-AT2 PCIe/")
		(sheetfile "x710-at2-pcie.kicad_sch")
		(attr smd)
		(fp_rect
			(start -0.925 -0.47)
			(end 0.925 0.47)
			(stroke
				(width 0.05)
				(type default)
			)
			(fill no)
			(layer "F.CrtYd")
		)
		(fp_line
			(start -0.494 0.248)
			(end -0.494 -0.25)
			(stroke
				(width 0.15)
				(type solid)
			)
			(layer "F.Fab")
		)
		(fp_line
			(start 0.504 0.248)
			(end -0.494 0.248)
			(stroke
				(width 0.15)
				(type solid)
			)
			(layer "F.Fab")
		)
		(fp_line
			(start -0.494 -0.25)
			(end 0.504 -0.25)
			(stroke
				(width 0.15)
				(type solid)
			)
			(layer "F.Fab")
		)
		(fp_line
			(start 0.504 -0.25)
			(end 0.504 0.248)
			(stroke
				(width 0.15)
				(type solid)
			)
			(layer "F.Fab")
		)
		(pad "1" smd roundrect
			(at -0.48 0 270)
			(size 0.59 0.64)
			(layers "F.Cu" "F.Mask" "F.Paste")
			(roundrect_rratio 0.25)
			(net 20 "/OCuLink/PCIe_{x4}.TX1-")
			(pintype "passive")
		)
		(pad "2" smd roundrect
			(at 0.48 0 270)
			(size 0.59 0.64)
			(layers "F.Cu" "F.Mask" "F.Paste")
			(roundrect_rratio 0.25)
			(net 38 "/X710-AT2 PCIe/PCIe_{x4}_AC.TX1-")
			(pintype "passive")
		)
	)
	(footprint "antmicro-footprints:R_0402_1005Metric"
		(layer "F.Cu")
		(at 58.24 80.7 -90)
		(descr "Resistor SMD 0402")
		(tags "resistor SMD 0402")
		(property "Reference" "R55"
			(at -1.77 -0.53 90)
			(layer "F.SilkS")
			(effects
				(font
					(size 0.7 0.7)
					(thickness 0.15)
				)
				(justify right top)
			)
		)
		(property "Value" "R_8k2_0402"
			(at -1.011843 1.772046 90)
			(layer "F.Fab")
			(hide yes)
			(effects
				(font
					(size 0.7 0.7)
					(thickness 0.15)
				)
				(justify right top)
			)
		)
		(property "Datasheet" "https://www.bourns.com/docs/product-datasheets/cr.pdf"
			(at 0 0 90)
			(layer "F.Fab")
			(hide yes)
			(effects
				(font
					(size 1.27 1.27)
					(thickness 0.15)
				)
			)
		)
		(property "Description" "SMD Chip Resistor"
			(at 0 0 90)
			(layer "F.Fab")
			(hide yes)
			(effects
				(font
					(size 1.27 1.27)
					(thickness 0.15)
				)
			)
		)
		(property "MPN" "CR0402-FX-8201GLF"
			(at 0 0 270)
			(unlocked yes)
			(layer "F.Fab")
			(hide yes)
			(effects
				(font
					(size 1 1)
					(thickness 0.15)
				)
			)
		)
		(property "Manufacturer" "Bourns"
			(at 0 0 270)
			(unlocked yes)
			(layer "F.Fab")
			(hide yes)
			(effects
				(font
					(size 1 1)
					(thickness 0.15)
				)
			)
		)
		(property "License" "Apache-2.0"
			(at 0 0 270)
			(unlocked yes)
			(layer "F.Fab")
			(hide yes)
			(effects
				(font
					(size 1 1)
					(thickness 0.15)
				)
			)
		)
		(property "Author" "Antmicro"
			(at 0 0 270)
			(unlocked yes)
			(layer "F.Fab")
			(hide yes)
			(effects
				(font
					(size 1 1)
					(thickness 0.15)
				)
			)
		)
		(property "Val" "8k2"
			(at 0 0 270)
			(unlocked yes)
			(layer "F.Fab")
			(hide yes)
			(effects
				(font
					(size 1 1)
					(thickness 0.15)
				)
			)
		)
		(property "Tolerance" "1%"
			(at 0 0 270)
			(unlocked yes)
			(layer "F.Fab")
			(hide yes)
			(effects
				(font
					(size 1 1)
					(thickness 0.15)
				)
			)
		)
		(sheetname "/X710-AT2 PCIe/")
		(sheetfile "x710-at2-pcie.kicad_sch")
		(attr smd)
		(fp_rect
			(start -0.925 -0.47)
			(end 0.925 0.47)
			(stroke
				(width 0.05)
				(type default)
			)
			(fill no)
			(layer "F.CrtYd")
		)
		(fp_rect
			(start -0.5 -0.25)
			(end 0.5 0.25)
			(stroke
				(width 0.15)
				(type solid)
			)
			(fill no)
			(layer "F.Fab")
		)
		(pad "1" smd roundrect
			(at -0.48 0 270)
			(size 0.59 0.64)
			(layers "F.Cu" "F.Mask" "F.Paste")
			(roundrect_rratio 0.25)
			(net 28 "GND")
			(pintype "passive")
		)
		(pad "2" smd roundrect
			(at 0.48 0 270)
			(size 0.59 0.64)
			(layers "F.Cu" "F.Mask" "F.Paste")
			(roundrect_rratio 0.25)
			(net 15 "/X710-AT2 PCIe/PCIe_JTAG.~{JRST}")
			(pintype "passive")
		)
	)
)
